# SCM (Grand Teton) — schematic netlist excerpt (pin names and nets, part order shuffled) for the footprints in the layout excerpt that follows; sources: Cadence DE-HDL packaged netlist, KiCad conversion of 12092022_DA0F0TMDCD0_F0T_Management_Board_D_brd_V3_OCP.brd

R453  Q_RES  0 5% CHIP  pkg 0402LF  page 35 : A = SMB_BMC_ALERT3_N ; B = SMB_BMC_ALERT3_R1_N
C129  Q_CAP  1UF 25V 10% X6S  pkg C0402  page 16 : A = P1V2_AUX ; B = GND

(kicad_pcb
	(version 20260206)
	(generator "pcbnew")
	(generator_version "10.0")
	(general
		(thickness 1.6)
		(legacy_teardrops no)
	)
	(paper "A4")
	(title_block
		(title "12092022_DA0F0TMDCD0_F0T_Management_Board_D_brd_V3_OCP.brd")
		(comment 1 "Grand Teton / footprints 723-724 of 1440")
	)
	(layers
		(0 "F.Cu" signal "TOP")
		(4 "In1.Cu" signal "GND")
		(6 "In2.Cu" signal "IN1")
		(8 "In3.Cu" signal "GND1")
		(10 "In4.Cu" signal "IN2")
		(12 "In5.Cu" signal "VCC")
		(14 "In6.Cu" signal "VCC1")
		(16 "In7.Cu" signal "IN3")
		(18 "In8.Cu" signal "GND2")
		(20 "In9.Cu" signal "IN4")
		(22 "In10.Cu" signal "GND3")
		(2 "B.Cu" signal "BOTTOM")
		(9 "F.Adhes" user "F.Adhesive")
		(11 "B.Adhes" user "B.Adhesive")
		(13 "F.Paste" user "Package Geometry/Pastemask Top")
		(15 "B.Paste" user "Package Geometry/Pastemask Bottom")
		(5 "F.SilkS" user "Ref Des/Silkscreen Top")
		(7 "B.SilkS" user "Ref Des/Silkscreen Bottom")
		(1 "F.Mask" user "Board Geometry/Soldermask Top")
		(3 "B.Mask" user "Board Geometry/Soldermask Bottom")
		(17 "Dwgs.User" user "User.Drawings")
		(19 "Cmts.User" user "User.Comments")
		(21 "Eco1.User" user "User.Eco1")
		(23 "Eco2.User" user "User.Eco2")
		(25 "Edge.Cuts" user "Board Geometry/Outline")
		(27 "Margin" user)
		(31 "F.CrtYd" user "Package Geometry/Place Bound Top")
		(29 "B.CrtYd" user "Package Geometry/Place Bound Bottom")
		(35 "F.Fab" user "Ref Des/Assembly Top")
		(33 "B.Fab" user "Ref Des/Assembly Bottom")
	)
	(footprint ""
		(layer "F.Cu")
		(at 72.277732 -35.154362 180)
		(property "Reference" "C129"
			(at 0 0 180)
			(layer "F.SilkS")
			(hide yes)
			(effects
				(font
					(size 1.27 1.27)
				)
			)
		)
		(property "Value" ""
			(at 0 0 180)
			(layer "F.Fab")
			(effects
				(font
					(size 1.27 1.27)
				)
			)
		)
		(duplicate_pad_numbers_are_jumpers no)
		(fp_line
			(start 0.7874 0.4064)
			(end -0.7874 0.4064)
			(stroke
				(width 0.1524)
				(type default)
			)
			(layer "F.SilkS")
		)
		(fp_line
			(start 0.7874 -0.4064)
			(end 0.7874 0.4064)
			(stroke
				(width 0.1524)
				(type default)
			)
			(layer "F.SilkS")
		)
		(fp_line
			(start -0.7874 0.4064)
			(end -0.7874 -0.4064)
			(stroke
				(width 0.1524)
				(type default)
			)
			(layer "F.SilkS")
		)
		(fp_line
			(start -0.7874 -0.4064)
			(end 0.7874 -0.4064)
			(stroke
				(width 0.1524)
				(type default)
			)
			(layer "F.SilkS")
		)
		(fp_line
			(start 0.67945 0.3048)
			(end 0.120396 0.3048)
			(stroke
				(width 0.1)
				(type default)
			)
			(layer "F.Fab")
		)
		(fp_line
			(start 0.67945 -0.3048)
			(end 0.67945 0.3048)
			(stroke
				(width 0.1)
				(type default)
			)
			(layer "F.Fab")
		)
		(fp_line
			(start 0.12065 -0.2794)
			(end 0.12065 -0.3048)
			(stroke
				(width 0.1)
				(type default)
			)
			(layer "F.Fab")
		)
		(fp_line
			(start 0.12065 -0.3048)
			(end 0.67945 -0.3048)
			(stroke
				(width 0.1)
				(type default)
			)
			(layer "F.Fab")
		)
		(fp_line
			(start 0.120396 0.3048)
			(end 0.120396 0.2794)
			(stroke
				(width 0.1)
				(type default)
			)
			(layer "F.Fab")
		)
		(fp_line
			(start 0.120396 0.2794)
			(end -0.12065 0.2794)
			(stroke
				(width 0.1)
				(type default)
			)
			(layer "F.Fab")
		)
		(fp_line
			(start -0.12065 0.3048)
			(end -0.67945 0.3048)
			(stroke
				(width 0.1)
				(type default)
			)
			(layer "F.Fab")
		)
		(fp_line
			(start -0.12065 0.2794)
			(end -0.12065 0.3048)
			(stroke
				(width 0.1)
				(type default)
			)
			(layer "F.Fab")
		)
		(fp_line
			(start -0.12065 -0.2794)
			(end 0.12065 -0.2794)
			(stroke
				(width 0.1)
				(type default)
			)
			(layer "F.Fab")
		)
		(fp_line
			(start -0.12065 -0.305054)
			(end -0.12065 -0.2794)
			(stroke
				(width 0.1)
				(type default)
			)
			(layer "F.Fab")
		)
		(fp_line
			(start -0.67945 0.3048)
			(end -0.67945 -0.305054)
			(stroke
				(width 0.1)
				(type default)
			)
			(layer "F.Fab")
		)
		(fp_line
			(start -0.67945 -0.305054)
			(end -0.12065 -0.305054)
			(stroke
				(width 0.1)
				(type default)
			)
			(layer "F.Fab")
		)
		(pad "1" smd circle
			(at -0.40005 0 180)
			(size 0 0)
			(layers "F.Cu" "F.Mask" "F.Paste")
			(net "P1V2_AUX")
		)
		(pad "2" smd circle
			(at 0.40005 0 180)
			(size 0 0)
			(layers "F.Cu" "F.Mask" "F.Paste")
			(net "GND")
		)
	)
	(footprint ""
		(layer "F.Cu")
		(at 12.319 -85.344)
		(property "Reference" "R453"
			(at 0 0 0)
			(layer "F.SilkS")
			(hide yes)
			(effects
				(font
					(size 1.27 1.27)
				)
			)
		)
		(property "Value" ""
			(at 0 0 0)
			(layer "F.Fab")
			(effects
				(font
					(size 1.27 1.27)
				)
			)
		)
		(duplicate_pad_numbers_are_jumpers no)
		(fp_line
			(start -0.7874 -0.4064)
			(end 0.7874 -0.4064)
			(stroke
				(width 0.1524)
				(type default)
			)
			(layer "F.SilkS")
		)
		(fp_line
			(start -0.7874 0.4064)
			(end -0.7874 -0.4064)
			(stroke
				(width 0.1524)
				(type default)
			)
			(layer "F.SilkS")
		)
		(fp_line
			(start 0.7874 -0.4064)
			(end 0.7874 0.4064)
			(stroke
				(width 0.1524)
				(type default)
			)
			(layer "F.SilkS")
		)
		(fp_line
			(start 0.7874 0.4064)
			(end -0.7874 0.4064)
			(stroke
				(width 0.1524)
				(type default)
			)
			(layer "F.SilkS")
		)
		(fp_line
			(start -0.67945 -0.305054)
			(end -0.12065 -0.305054)
			(stroke
				(width 0.1)
				(type default)
			)
			(layer "F.Fab")
		)
		(fp_line
			(start -0.67945 0.3048)
			(end -0.67945 -0.305054)
			(stroke
				(width 0.1)
				(type default)
			)
			(layer "F.Fab")
		)
		(fp_line
			(start -0.12065 -0.305054)
			(end -0.12065 -0.2794)
			(stroke
				(width 0.1)
				(type default)
			)
			(layer "F.Fab")
		)
		(fp_line
			(start -0.12065 -0.2794)
			(end 0.12065 -0.2794)
			(stroke
				(width 0.1)
				(type default)
			)
			(layer "F.Fab")
		)
		(fp_line
			(start -0.12065 0.2794)
			(end -0.12065 0.3048)
			(stroke
				(width 0.1)
				(type default)
			)
			(layer "F.Fab")
		)
		(fp_line
			(start -0.12065 0.3048)
			(end -0.67945 0.3048)
			(stroke
				(width 0.1)
				(type default)
			)
			(layer "F.Fab")
		)
		(fp_line
			(start 0.120396 0.2794)
			(end -0.12065 0.2794)
			(stroke
				(width 0.1)
				(type default)
			)
			(layer "F.Fab")
		)
		(fp_line
			(start 0.120396 0.3048)
			(end 0.120396 0.2794)
			(stroke
				(width 0.1)
				(type default)
			)
			(layer "F.Fab")
		)
		(fp_line
			(start 0.12065 -0.3048)
			(end 0.67945 -0.3048)
			(stroke
				(width 0.1)
				(type default)
			)
			(layer "F.Fab")
		)
		(fp_line
			(start 0.12065 -0.2794)
			(end 0.12065 -0.3048)
			(stroke
				(width 0.1)
				(type default)
			)
			(layer "F.Fab")
		)
		(fp_line
			(start 0.67945 -0.3048)
			(end 0.67945 0.3048)
			(stroke
				(width 0.1)
				(type default)
			)
			(layer "F.Fab")
		)
		(fp_line
			(start 0.67945 0.3048)
			(end 0.120396 0.3048)
			(stroke
				(width 0.1)
				(type default)
			)
			(layer "F.Fab")
		)
		(pad "1" smd circle
			(at -0.40005 0)
			(size 0 0)
			(layers "F.Cu" "F.Mask" "F.Paste")
			(net "SMB_BMC_ALERT3_N")
		)
		(pad "2" smd circle
			(at 0.40005 0)
			(size 0 0)
			(layers "F.Cu" "F.Mask" "F.Paste")
			(net "SMB_BMC_ALERT3_R1_N")
		)
	)
)
